(kicad_pcb
	(version 20260206)
	(generator "pcbnew")
	(generator_version "10.0")
	(general
		(thickness 1.6)
		(legacy_teardrops no)
	)
	(paper "A4")
	(title_block
		(title "03242023_DA0F0TMBIJ0_F0T_Motherboard_J_brd_V01_OCP.brd")
		(comment 1 "Grand Teton / footprints 3640-3646 of 6105")
	)
	(layers
		(0 "F.Cu" signal "TOP")
		(4 "In1.Cu" signal "GND")
		(6 "In2.Cu" signal "IN1")
		(8 "In3.Cu" signal "GND1")
		(10 "In4.Cu" signal "IN2")
		(12 "In5.Cu" signal "GND2")
		(14 "In6.Cu" signal "IN3")
		(16 "In7.Cu" signal "GND3")
		(18 "In8.Cu" signal "VCC")
		(20 "In9.Cu" signal "VCC1")
		(22 "In10.Cu" signal "GND4")
		(24 "In11.Cu" signal "IN4")
		(26 "In12.Cu" signal "GND5")
		(28 "In13.Cu" signal "IN5")
		(30 "In14.Cu" signal "GND6")
		(32 "In15.Cu" signal "IN6")
		(34 "In16.Cu" signal "GND7")
		(2 "B.Cu" signal "BOTTOM")
		(9 "F.Adhes" user "F.Adhesive")
		(11 "B.Adhes" user "B.Adhesive")
		(13 "F.Paste" user "Package Geometry/Pastemask Top")
		(15 "B.Paste" user "Package Geometry/Pastemask Bottom")
		(5 "F.SilkS" user "Ref Des/Silkscreen Top")
		(7 "B.SilkS" user "Ref Des/Silkscreen Bottom")
		(1 "F.Mask" user "Board Geometry/Soldermask Top")
		(3 "B.Mask" user "Board Geometry/Soldermask Bottom")
		(17 "Dwgs.User" user "User.Drawings")
		(19 "Cmts.User" user "User.Comments")
		(21 "Eco1.User" user "User.Eco1")
		(23 "Eco2.User" user "User.Eco2")
		(25 "Edge.Cuts" user "Board Geometry/Outline")
		(27 "Margin" user)
		(31 "F.CrtYd" user "Package Geometry/Place Bound Top")
		(29 "B.CrtYd" user "Package Geometry/Place Bound Bottom")
		(35 "F.Fab" user "Ref Des/Assembly Top")
		(33 "B.Fab" user "Ref Des/Assembly Bottom")
	)
	(footprint ""
		(layer "F.Cu")
		(at 421.15359 -163.477194 -90)
		(property "Reference" "PR2718"
			(at 0 0 270)
			(layer "F.SilkS")
			(hide yes)
			(effects
				(font
					(size 1.27 1.27)
				)
			)
		)
		(property "Value" ""
			(at 0 0 270)
			(layer "F.Fab")
			(effects
				(font
					(size 1.27 1.27)
				)
			)
		)
		(duplicate_pad_numbers_are_jumpers no)
		(fp_line
			(start -0.7874 0.4064)
			(end -0.7874 -0.4064)
			(stroke
				(width 0.1524)
				(type default)
			)
			(layer "F.SilkS")
		)
		(fp_line
			(start 0.7874 0.4064)
			(end -0.7874 0.4064)
			(stroke
				(width 0.1524)
				(type default)
			)
			(layer "F.SilkS")
		)
		(fp_line
			(start -0.7874 -0.4064)
			(end 0.7874 -0.4064)
			(stroke
				(width 0.1524)
				(type default)
			)
			(layer "F.SilkS")
		)
		(fp_line
			(start 0.7874 -0.4064)
			(end 0.7874 0.4064)
			(stroke
				(width 0.1524)
				(type default)
			)
			(layer "F.SilkS")
		)
		(fp_line
			(start -0.67945 0.3048)
			(end -0.67945 -0.305054)
			(stroke
				(width 0.1)
				(type default)
			)
			(layer "F.Fab")
		)
		(fp_line
			(start -0.12065 0.3048)
			(end -0.67945 0.3048)
			(stroke
				(width 0.1)
				(type default)
			)
			(layer "F.Fab")
		)
		(fp_line
			(start 0.120396 0.3048)
			(end 0.120396 0.2794)
			(stroke
				(width 0.1)
				(type default)
			)
			(layer "F.Fab")
		)
		(fp_line
			(start 0.67945 0.3048)
			(end 0.120396 0.3048)
			(stroke
				(width 0.1)
				(type default)
			)
			(layer "F.Fab")
		)
		(fp_line
			(start -0.12065 0.2794)
			(end -0.12065 0.3048)
			(stroke
				(width 0.1)
				(type default)
			)
			(layer "F.Fab")
		)
		(fp_line
			(start 0.120396 0.2794)
			(end -0.12065 0.2794)
			(stroke
				(width 0.1)
				(type default)
			)
			(layer "F.Fab")
		)
		(fp_line
			(start -0.12065 -0.2794)
			(end 0.12065 -0.2794)
			(stroke
				(width 0.1)
				(type default)
			)
			(layer "F.Fab")
		)
		(fp_line
			(start 0.12065 -0.2794)
			(end 0.12065 -0.3048)
			(stroke
				(width 0.1)
				(type default)
			)
			(layer "F.Fab")
		)
		(fp_line
			(start 0.12065 -0.3048)
			(end 0.67945 -0.3048)
			(stroke
				(width 0.1)
				(type default)
			)
			(layer "F.Fab")
		)
		(fp_line
			(start 0.67945 -0.3048)
			(end 0.67945 0.3048)
			(stroke
				(width 0.1)
				(type default)
			)
			(layer "F.Fab")
		)
		(fp_line
			(start -0.67945 -0.305054)
			(end -0.12065 -0.305054)
			(stroke
				(width 0.1)
				(type default)
			)
			(layer "F.Fab")
		)
		(fp_line
			(start -0.12065 -0.305054)
			(end -0.12065 -0.2794)
			(stroke
				(width 0.1)
				(type default)
			)
			(layer "F.Fab")
		)
		(pad "1" smd circle
			(at -0.40005 0 270)
			(size 0 0)
			(layers "F.Cu" "F.Mask" "F.Paste")
			(net "PVCCD_HV_CPU0_LSET1")
		)
		(pad "2" smd circle
			(at 0.40005 0 270)
			(size 0 0)
			(layers "F.Cu" "F.Mask" "F.Paste")
			(net "GND")
		)
	)
	(footprint ""
		(layer "F.Cu")
		(at 119.508016 -255.0541 90)
		(property "Reference" "C268"
			(at 0 0 90)
			(layer "F.SilkS")
			(hide yes)
			(effects
				(font
					(size 1.27 1.27)
				)
			)
		)
		(property "Value" ""
			(at 0 0 90)
			(layer "F.Fab")
			(effects
				(font
					(size 1.27 1.27)
				)
			)
		)
		(duplicate_pad_numbers_are_jumpers no)
		(fp_line
			(start 0.7874 -0.4064)
			(end 0.7874 0.4064)
			(stroke
				(width 0.1524)
				(type default)
			)
			(layer "F.SilkS")
		)
		(fp_line
			(start -0.7874 -0.4064)
			(end 0.7874 -0.4064)
			(stroke
				(width 0.1524)
				(type default)
			)
			(layer "F.SilkS")
		)
		(fp_line
			(start 0.7874 0.4064)
			(end -0.7874 0.4064)
			(stroke
				(width 0.1524)
				(type default)
			)
			(layer "F.SilkS")
		)
		(fp_line
			(start -0.7874 0.4064)
			(end -0.7874 -0.4064)
			(stroke
				(width 0.1524)
				(type default)
			)
			(layer "F.SilkS")
		)
		(fp_line
			(start -0.12065 -0.305054)
			(end -0.12065 -0.2794)
			(stroke
				(width 0.1)
				(type default)
			)
			(layer "F.Fab")
		)
		(fp_line
			(start -0.67945 -0.305054)
			(end -0.12065 -0.305054)
			(stroke
				(width 0.1)
				(type default)
			)
			(layer "F.Fab")
		)
		(fp_line
			(start 0.67945 -0.3048)
			(end 0.67945 0.3048)
			(stroke
				(width 0.1)
				(type default)
			)
			(layer "F.Fab")
		)
		(fp_line
			(start 0.12065 -0.3048)
			(end 0.67945 -0.3048)
			(stroke
				(width 0.1)
				(type default)
			)
			(layer "F.Fab")
		)
		(fp_line
			(start 0.12065 -0.2794)
			(end 0.12065 -0.3048)
			(stroke
				(width 0.1)
				(type default)
			)
			(layer "F.Fab")
		)
		(fp_line
			(start -0.12065 -0.2794)
			(end 0.12065 -0.2794)
			(stroke
				(width 0.1)
				(type default)
			)
			(layer "F.Fab")
		)
		(fp_line
			(start 0.120396 0.2794)
			(end -0.12065 0.2794)
			(stroke
				(width 0.1)
				(type default)
			)
			(layer "F.Fab")
		)
		(fp_line
			(start -0.12065 0.2794)
			(end -0.12065 0.3048)
			(stroke
				(width 0.1)
				(type default)
			)
			(layer "F.Fab")
		)
		(fp_line
			(start 0.67945 0.3048)
			(end 0.120396 0.3048)
			(stroke
				(width 0.1)
				(type default)
			)
			(layer "F.Fab")
		)
		(fp_line
			(start 0.120396 0.3048)
			(end 0.120396 0.2794)
			(stroke
				(width 0.1)
				(type default)
			)
			(layer "F.Fab")
		)
		(fp_line
			(start -0.12065 0.3048)
			(end -0.67945 0.3048)
			(stroke
				(width 0.1)
				(type default)
			)
			(layer "F.Fab")
		)
		(fp_line
			(start -0.67945 0.3048)
			(end -0.67945 -0.305054)
			(stroke
				(width 0.1)
				(type default)
			)
			(layer "F.Fab")
		)
		(pad "1" smd circle
			(at -0.40005 0 90)
			(size 0 0)
			(layers "F.Cu" "F.Mask" "F.Paste")
			(net "PVCCIN_CPU1")
		)
		(pad "2" smd circle
			(at 0.40005 0 90)
			(size 0 0)
			(layers "F.Cu" "F.Mask" "F.Paste")
			(net "GND")
		)
	)
	(footprint ""
		(layer "F.Cu")
		(at 382.968754 -347.509846 -90)
		(property "Reference" "PC1344"
			(at 0 0 270)
			(layer "F.SilkS")
			(hide yes)
			(effects
				(font
					(size 1.27 1.27)
				)
			)
		)
		(property "Value" ""
			(at 0 0 270)
			(layer "F.Fab")
			(effects
				(font
					(size 1.27 1.27)
				)
			)
		)
		(duplicate_pad_numbers_are_jumpers no)
		(fp_line
			(start -0.7874 0.4064)
			(end -0.7874 -0.4064)
			(stroke
				(width 0.1524)
				(type default)
			)
			(layer "F.SilkS")
		)
		(fp_line
			(start 0.7874 0.4064)
			(end -0.7874 0.4064)
			(stroke
				(width 0.1524)
				(type default)
			)
			(layer "F.SilkS")
		)
		(fp_line
			(start -0.7874 -0.4064)
			(end 0.7874 -0.4064)
			(stroke
				(width 0.1524)
				(type default)
			)
			(layer "F.SilkS")
		)
		(fp_line
			(start 0.7874 -0.4064)
			(end 0.7874 0.4064)
			(stroke
				(width 0.1524)
				(type default)
			)
			(layer "F.SilkS")
		)
		(fp_line
			(start -0.67945 0.3048)
			(end -0.67945 -0.305054)
			(stroke
				(width 0.1)
				(type default)
			)
			(layer "F.Fab")
		)
		(fp_line
			(start -0.12065 0.3048)
			(end -0.67945 0.3048)
			(stroke
				(width 0.1)
				(type default)
			)
			(layer "F.Fab")
		)
		(fp_line
			(start 0.120396 0.3048)
			(end 0.120396 0.2794)
			(stroke
				(width 0.1)
				(type default)
			)
			(layer "F.Fab")
		)
		(fp_line
			(start 0.67945 0.3048)
			(end 0.120396 0.3048)
			(stroke
				(width 0.1)
				(type default)
			)
			(layer "F.Fab")
		)
		(fp_line
			(start -0.12065 0.2794)
			(end -0.12065 0.3048)
			(stroke
				(width 0.1)
				(type default)
			)
			(layer "F.Fab")
		)
		(fp_line
			(start 0.120396 0.2794)
			(end -0.12065 0.2794)
			(stroke
				(width 0.1)
				(type default)
			)
			(layer "F.Fab")
		)
		(fp_line
			(start -0.12065 -0.2794)
			(end 0.12065 -0.2794)
			(stroke
				(width 0.1)
				(type default)
			)
			(layer "F.Fab")
		)
		(fp_line
			(start 0.12065 -0.2794)
			(end 0.12065 -0.3048)
			(stroke
				(width 0.1)
				(type default)
			)
			(layer "F.Fab")
		)
		(fp_line
			(start 0.12065 -0.3048)
			(end 0.67945 -0.3048)
			(stroke
				(width 0.1)
				(type default)
			)
			(layer "F.Fab")
		)
		(fp_line
			(start 0.67945 -0.3048)
			(end 0.67945 0.3048)
			(stroke
				(width 0.1)
				(type default)
			)
			(layer "F.Fab")
		)
		(fp_line
			(start -0.67945 -0.305054)
			(end -0.12065 -0.305054)
			(stroke
				(width 0.1)
				(type default)
			)
			(layer "F.Fab")
		)
		(fp_line
			(start -0.12065 -0.305054)
			(end -0.12065 -0.2794)
			(stroke
				(width 0.1)
				(type default)
			)
			(layer "F.Fab")
		)
		(pad "1" smd circle
			(at -0.40005 0 270)
			(size 0 0)
			(layers "F.Cu" "F.Mask" "F.Paste")
			(net "GND")
		)
		(pad "2" smd circle
			(at 0.40005 0 270)
			(size 0 0)
			(layers "F.Cu" "F.Mask" "F.Paste")
			(net "PVCCIN_CPU0_VREF")
		)
	)
	(footprint ""
		(layer "F.Cu")
		(at 307.14188 -49.621948 180)
		(property "Reference" "R497"
			(at 0 0 180)
			(layer "F.SilkS")
			(hide yes)
			(effects
				(font
					(size 1.27 1.27)
				)
			)
		)
		(property "Value" ""
			(at 0 0 180)
			(layer "F.Fab")
			(effects
				(font
					(size 1.27 1.27)
				)
			)
		)
		(duplicate_pad_numbers_are_jumpers no)
		(fp_line
			(start 0.7874 0.4064)
			(end -0.7874 0.4064)
			(stroke
				(width 0.1524)
				(type default)
			)
			(layer "F.SilkS")
		)
		(fp_line
			(start 0.7874 -0.4064)
			(end 0.7874 0.4064)
			(stroke
				(width 0.1524)
				(type default)
			)
			(layer "F.SilkS")
		)
		(fp_line
			(start -0.7874 0.4064)
			(end -0.7874 -0.4064)
			(stroke
				(width 0.1524)
				(type default)
			)
			(layer "F.SilkS")
		)
		(fp_line
			(start -0.7874 -0.4064)
			(end 0.7874 -0.4064)
			(stroke
				(width 0.1524)
				(type default)
			)
			(layer "F.SilkS")
		)
		(fp_line
			(start 0.67945 0.3048)
			(end 0.120396 0.3048)
			(stroke
				(width 0.1)
				(type default)
			)
			(layer "F.Fab")
		)
		(fp_line
			(start 0.67945 -0.3048)
			(end 0.67945 0.3048)
			(stroke
				(width 0.1)
				(type default)
			)
			(layer "F.Fab")
		)
		(fp_line
			(start 0.12065 -0.2794)
			(end 0.12065 -0.3048)
			(stroke
				(width 0.1)
				(type default)
			)
			(layer "F.Fab")
		)
		(fp_line
			(start 0.12065 -0.3048)
			(end 0.67945 -0.3048)
			(stroke
				(width 0.1)
				(type default)
			)
			(layer "F.Fab")
		)
		(fp_line
			(start 0.120396 0.3048)
			(end 0.120396 0.2794)
			(stroke
				(width 0.1)
				(type default)
			)
			(layer "F.Fab")
		)
		(fp_line
			(start 0.120396 0.2794)
			(end -0.12065 0.2794)
			(stroke
				(width 0.1)
				(type default)
			)
			(layer "F.Fab")
		)
		(fp_line
			(start -0.12065 0.3048)
			(end -0.67945 0.3048)
			(stroke
				(width 0.1)
				(type default)
			)
			(layer "F.Fab")
		)
		(fp_line
			(start -0.12065 0.2794)
			(end -0.12065 0.3048)
			(stroke
				(width 0.1)
				(type default)
			)
			(layer "F.Fab")
		)
		(fp_line
			(start -0.12065 -0.2794)
			(end 0.12065 -0.2794)
			(stroke
				(width 0.1)
				(type default)
			)
			(layer "F.Fab")
		)
		(fp_line
			(start -0.12065 -0.305054)
			(end -0.12065 -0.2794)
			(stroke
				(width 0.1)
				(type default)
			)
			(layer "F.Fab")
		)
		(fp_line
			(start -0.67945 0.3048)
			(end -0.67945 -0.305054)
			(stroke
				(width 0.1)
				(type default)
			)
			(layer "F.Fab")
		)
		(fp_line
			(start -0.67945 -0.305054)
			(end -0.12065 -0.305054)
			(stroke
				(width 0.1)
				(type default)
			)
			(layer "F.Fab")
		)
		(pad "1" smd circle
			(at -0.40005 0 180)
			(size 0 0)
			(layers "F.Cu" "F.Mask" "F.Paste")
			(net "PD_RCOMP_1P8_3P3")
		)
		(pad "2" smd circle
			(at 0.40005 0 180)
			(size 0 0)
			(layers "F.Cu" "F.Mask" "F.Paste")
			(net "GND")
		)
	)
	(footprint ""
		(layer "F.Cu")
		(at 244.750844 -407.411936 -90)
		(property "Reference" "PR4"
			(at 0 0 270)
			(layer "F.SilkS")
			(hide yes)
			(effects
				(font
					(size 1.27 1.27)
				)
			)
		)
		(property "Value" ""
			(at 0 0 270)
			(layer "F.Fab")
			(effects
				(font
					(size 1.27 1.27)
				)
			)
		)
		(duplicate_pad_numbers_are_jumpers no)
		(fp_line
			(start -3.9878 3.5814)
			(end -3.9878 -3.5814)
			(stroke
				(width 0.1524)
				(type default)
			)
			(layer "F.SilkS")
		)
		(fp_line
			(start 3.9878 3.5814)
			(end -3.9878 3.5814)
			(stroke
				(width 0.1524)
				(type default)
			)
			(layer "F.SilkS")
		)
		(fp_line
			(start -3.9878 -3.5814)
			(end 3.9878 -3.5814)
			(stroke
				(width 0.1524)
				(type default)
			)
			(layer "F.SilkS")
		)
		(fp_line
			(start 3.9878 -3.5814)
			(end 3.9878 3.5814)
			(stroke
				(width 0.1524)
				(type default)
			)
			(layer "F.SilkS")
		)
		(fp_line
			(start -3.5306 3.353054)
			(end -3.5306 -3.353054)
			(stroke
				(width 0.1)
				(type default)
			)
			(layer "F.Fab")
		)
		(fp_line
			(start 3.5306 3.353054)
			(end -3.5306 3.353054)
			(stroke
				(width 0.1)
				(type default)
			)
			(layer "F.Fab")
		)
		(fp_line
			(start -3.5306 -3.353054)
			(end 3.5306 -3.353054)
			(stroke
				(width 0.1)
				(type default)
			)
			(layer "F.Fab")
		)
		(fp_line
			(start 3.5306 -3.353054)
			(end 3.5306 3.353054)
			(stroke
				(width 0.1)
				(type default)
			)
			(layer "F.Fab")
		)
		(pad "1A" smd rect
			(at -2.249932 0 90)
			(size 3.2004 6.858)
			(layers "F.Cu" "F.Mask" "F.Paste")
			(net "P12V_PSU")
		)
		(pad "1B" smd rect
			(at -0.776732 0 270)
			(size 0.254 0.508)
			(layers "F.Cu" "F.Mask" "F.Paste")
			(net "P12V_HSC_SENSE2_R1_P")
		)
		(pad "2A" smd rect
			(at 2.249932 0 90)
			(size 3.2004 6.858)
			(layers "F.Cu" "F.Mask" "F.Paste")
			(net "P12V_MAIN_R")
		)
		(pad "2B" smd rect
			(at 0.776732 0 270)
			(size 0.254 0.508)
			(layers "F.Cu" "F.Mask" "F.Paste")
			(net "P12V_HSC_SENSE2_R1_N")
		)
	)
	(footprint ""
		(layer "F.Cu")
		(at 143.764 -25.110948 180)
		(property "Reference" "R4628"
			(at 0 0 180)
			(layer "F.SilkS")
			(hide yes)
			(effects
				(font
					(size 1.27 1.27)
				)
			)
		)
		(property "Value" ""
			(at 0 0 180)
			(layer "F.Fab")
			(effects
				(font
					(size 1.27 1.27)
				)
			)
		)
		(duplicate_pad_numbers_are_jumpers no)
		(fp_line
			(start 0.7874 0.4064)
			(end -0.7874 0.4064)
			(stroke
				(width 0.1524)
				(type default)
			)
			(layer "F.SilkS")
		)
		(fp_line
			(start 0.7874 -0.4064)
			(end 0.7874 0.4064)
			(stroke
				(width 0.1524)
				(type default)
			)
			(layer "F.SilkS")
		)
		(fp_line
			(start -0.7874 0.4064)
			(end -0.7874 -0.4064)
			(stroke
				(width 0.1524)
				(type default)
			)
			(layer "F.SilkS")
		)
		(fp_line
			(start -0.7874 -0.4064)
			(end 0.7874 -0.4064)
			(stroke
				(width 0.1524)
				(type default)
			)
			(layer "F.SilkS")
		)
		(fp_line
			(start 0.67945 0.3048)
			(end 0.120396 0.3048)
			(stroke
				(width 0.1)
				(type default)
			)
			(layer "F.Fab")
		)
		(fp_line
			(start 0.67945 -0.3048)
			(end 0.67945 0.3048)
			(stroke
				(width 0.1)
				(type default)
			)
			(layer "F.Fab")
		)
		(fp_line
			(start 0.12065 -0.2794)
			(end 0.12065 -0.3048)
			(stroke
				(width 0.1)
				(type default)
			)
			(layer "F.Fab")
		)
		(fp_line
			(start 0.12065 -0.3048)
			(end 0.67945 -0.3048)
			(stroke
				(width 0.1)
				(type default)
			)
			(layer "F.Fab")
		)
		(fp_line
			(start 0.120396 0.3048)
			(end 0.120396 0.2794)
			(stroke
				(width 0.1)
				(type default)
			)
			(layer "F.Fab")
		)
		(fp_line
			(start 0.120396 0.2794)
			(end -0.12065 0.2794)
			(stroke
				(width 0.1)
				(type default)
			)
			(layer "F.Fab")
		)
		(fp_line
			(start -0.12065 0.3048)
			(end -0.67945 0.3048)
			(stroke
				(width 0.1)
				(type default)
			)
			(layer "F.Fab")
		)
		(fp_line
			(start -0.12065 0.2794)
			(end -0.12065 0.3048)
			(stroke
				(width 0.1)
				(type default)
			)
			(layer "F.Fab")
		)
		(fp_line
			(start -0.12065 -0.2794)
			(end 0.12065 -0.2794)
			(stroke
				(width 0.1)
				(type default)
			)
			(layer "F.Fab")
		)
		(fp_line
			(start -0.12065 -0.305054)
			(end -0.12065 -0.2794)
			(stroke
				(width 0.1)
				(type default)
			)
			(layer "F.Fab")
		)
		(fp_line
			(start -0.67945 0.3048)
			(end -0.67945 -0.305054)
			(stroke
				(width 0.1)
				(type default)
			)
			(layer "F.Fab")
		)
		(fp_line
			(start -0.67945 -0.305054)
			(end -0.12065 -0.305054)
			(stroke
				(width 0.1)
				(type default)
			)
			(layer "F.Fab")
		)
		(pad "1" smd circle
			(at -0.40005 0 180)
			(size 0 0)
			(layers "F.Cu" "F.Mask" "F.Paste")
			(net "JTAG_BMC_TMS")
		)
		(pad "2" smd circle
			(at 0.40005 0 180)
			(size 0 0)
			(layers "F.Cu" "F.Mask" "F.Paste")
			(net "JTAG_BMC_TMS_R")
		)
	)
	(footprint ""
		(layer "F.Cu")
		(at 145.46326 -338.393532 90)
		(property "Reference" "PL106"
			(at -4.419854 0.37338 0)
			(unlocked yes)
			(layer "F.SilkS")
			(effects
				(font
					(size 0.7874 0.5842)
					(thickness 0.1524)
				)
				(justify left)
			)
		)
		(property "Value" ""
			(at 0 0 90)
			(layer "F.Fab")
			(effects
				(font
					(size 1.27 1.27)
				)
			)
		)
		(duplicate_pad_numbers_are_jumpers no)
		(fp_line
			(start 3.24993 -3.24993)
			(end 3.24993 -2.2352)
			(stroke
				(width 0.1524)
				(type default)
			)
			(layer "F.SilkS")
		)
		(fp_line
			(start -3.24993 -3.24993)
			(end 3.24993 -3.24993)
			(stroke
				(width 0.1524)
				(type default)
			)
			(layer "F.SilkS")
		)
		(fp_line
			(start -3.24993 -2.2352)
			(end -3.24993 -3.24993)
			(stroke
				(width 0.1524)
				(type default)
			)
			(layer "F.SilkS")
		)
		(fp_line
			(start 3.24993 2.2352)
			(end 3.24993 3.24993)
			(stroke
				(width 0.1524)
				(type default)
			)
			(layer "F.SilkS")
		)
		(fp_line
			(start 3.24993 3.24993)
			(end -3.24993 3.24993)
			(stroke
				(width 0.1524)
				(type default)
			)
			(layer "F.SilkS")
		)
		(fp_line
			(start -3.24993 3.24993)
			(end -3.24993 2.2352)
			(stroke
				(width 0.1524)
				(type default)
			)
			(layer "F.SilkS")
		)
		(fp_line
			(start 3.24993 -3.24993)
			(end 3.24993 3.24993)
			(stroke
				(width 0.1)
				(type default)
			)
			(layer "F.Fab")
		)
		(fp_line
			(start -3.24993 -3.24993)
			(end 3.24993 -3.24993)
			(stroke
				(width 0.1)
				(type default)
			)
			(layer "F.Fab")
		)
		(fp_line
			(start 3.24993 3.24993)
			(end -3.24993 3.24993)
			(stroke
				(width 0.1)
				(type default)
			)
			(layer "F.Fab")
		)
		(fp_line
			(start -3.24993 3.24993)
			(end -3.24993 -3.24993)
			(stroke
				(width 0.1)
				(type default)
			)
			(layer "F.Fab")
		)
		(pad "1" smd rect
			(at -2.29997 0 90)
			(size 2.0066 4.2164)
			(layers "F.Cu" "F.Mask" "F.Paste")
			(net "IND_P1_CPL8")
		)
		(pad "2" smd rect
			(at 2.29997 0 90)
			(size 2.0066 4.2164)
			(layers "F.Cu" "F.Mask" "F.Paste")
			(net "GND")
		)
	)
)
